(kicad_pcb
	(version 20260206)
	(generator "pcbnew")
	(generator_version "10.0")
	(general
		(thickness 1.6)
		(legacy_teardrops no)
	)
	(paper "A4")
	(title_block
		(title "v1-chassis-manager — T6M_CM_d_v01_1031_1645.brd")
		(comment 1 "Open CloudServer (Microsoft) / footprints 2364-2373 of 2512")
	)
	(layers
		(0 "F.Cu" signal "TOP")
		(4 "In1.Cu" signal "GND1")
		(6 "In2.Cu" signal "IN1")
		(8 "In3.Cu" signal "VCC1")
		(10 "In4.Cu" signal "VCC2")
		(12 "In5.Cu" signal "GND2")
		(14 "In6.Cu" signal "IN2")
		(16 "In7.Cu" signal "IN3")
		(18 "In8.Cu" signal "GND3")
		(2 "B.Cu" signal "BOTTOM")
		(9 "F.Adhes" user "F.Adhesive")
		(11 "B.Adhes" user "B.Adhesive")
		(13 "F.Paste" user "Package Geometry/Pastemask Top")
		(15 "B.Paste" user "Package Geometry/Pastemask Bottom")
		(5 "F.SilkS" user "Ref Des/Silkscreen Top")
		(7 "B.SilkS" user "Ref Des/Silkscreen Bottom")
		(1 "F.Mask" user "Board Geometry/Soldermask Top")
		(3 "B.Mask" user "Board Geometry/Soldermask Bottom")
		(17 "Dwgs.User" user "User.Drawings")
		(19 "Cmts.User" user "User.Comments")
		(21 "Eco1.User" user "User.Eco1")
		(23 "Eco2.User" user "User.Eco2")
		(25 "Edge.Cuts" user "Board Geometry/Outline")
		(27 "Margin" user)
		(31 "F.CrtYd" user "Package Geometry/Place Bound Top")
		(29 "B.CrtYd" user "Package Geometry/Place Bound Bottom")
		(35 "F.Fab" user "Ref Des/Assembly Top")
		(33 "B.Fab" user "Ref Des/Assembly Bottom")
	)
	(footprint ""
		(layer "B.Cu")
		(at 105.14076 -188.126624 -90)
		(property "Reference" "C662"
			(at -4.10337 0.070358 270)
			(unlocked yes)
			(layer "B.SilkS")
			(effects
				(font
					(size 0.7874 0.5842)
					(thickness 0.1524)
				)
				(justify left mirror)
			)
		)
		(property "Value" ""
			(at 0 0 90)
			(layer "B.Fab")
			(effects
				(font
					(size 1.27 1.27)
				)
				(justify mirror)
			)
		)
		(duplicate_pad_numbers_are_jumpers no)
		(fp_line
			(start -0.7874 0.4064)
			(end 0.7874 0.4064)
			(stroke
				(width 0.1524)
				(type default)
			)
			(layer "B.SilkS")
		)
		(fp_line
			(start 0.7874 0.4064)
			(end 0.7874 -0.4064)
			(stroke
				(width 0.1524)
				(type default)
			)
			(layer "B.SilkS")
		)
		(fp_line
			(start 0 0.381)
			(end 0 -0.381)
			(stroke
				(width 0.1524)
				(type default)
			)
			(layer "B.SilkS")
		)
		(fp_line
			(start -0.7874 -0.4064)
			(end -0.7874 0.4064)
			(stroke
				(width 0.1524)
				(type default)
			)
			(layer "B.SilkS")
		)
		(fp_line
			(start 0.7874 -0.4064)
			(end -0.7874 -0.4064)
			(stroke
				(width 0.1524)
				(type default)
			)
			(layer "B.SilkS")
		)
		(fp_poly
			(pts
				(xy 0.5334 0.254) (xy 0.635 0.254) (xy 0.635 0.2286) (xy 0.635 -0.254) (xy 0.5334 -0.254) (xy 0.5334 -0.2794)
				(xy -0.5334 -0.2794) (xy -0.5334 -0.254) (xy -0.635 -0.254) (xy -0.635 0.254) (xy -0.5334 0.254)
				(xy -0.5334 0.2794) (xy 0.508 0.2794) (xy 0.5334 0.2794)
			)
			(stroke
				(width 0)
				(type default)
			)
			(fill no)
			(layer "B.CrtYd")
		)
		(pad "1" smd rect
			(at -0.40005 0 90)
			(size 0.4572 0.508)
			(layers "B.Cu" "B.Mask" "B.Paste")
			(net "T5_NODE2_EN_R")
		)
		(pad "2" smd rect
			(at 0.40005 0 90)
			(size 0.4572 0.508)
			(layers "B.Cu" "B.Mask" "B.Paste")
			(net "GND")
		)
	)
	(footprint ""
		(layer "B.Cu")
		(at 54.469538 -78.515718)
		(property "Reference" "C104"
			(at -12.341098 31.108904 0)
			(unlocked yes)
			(layer "B.SilkS")
			(effects
				(font
					(size 0.7874 0.5842)
					(thickness 0.1524)
				)
				(justify left mirror)
			)
		)
		(property "Value" ""
			(at 0 0 0)
			(layer "B.Fab")
			(effects
				(font
					(size 1.27 1.27)
				)
				(justify mirror)
			)
		)
		(duplicate_pad_numbers_are_jumpers no)
		(fp_line
			(start -0.7874 -0.4064)
			(end -0.7874 0.4064)
			(stroke
				(width 0.1524)
				(type default)
			)
			(layer "B.SilkS")
		)
		(fp_line
			(start -0.7874 0.4064)
			(end 0.7874 0.4064)
			(stroke
				(width 0.1524)
				(type default)
			)
			(layer "B.SilkS")
		)
		(fp_line
			(start 0 0.381)
			(end 0 -0.381)
			(stroke
				(width 0.1524)
				(type default)
			)
			(layer "B.SilkS")
		)
		(fp_line
			(start 0.7874 -0.4064)
			(end -0.7874 -0.4064)
			(stroke
				(width 0.1524)
				(type default)
			)
			(layer "B.SilkS")
		)
		(fp_line
			(start 0.7874 0.4064)
			(end 0.7874 -0.4064)
			(stroke
				(width 0.1524)
				(type default)
			)
			(layer "B.SilkS")
		)
		(fp_poly
			(pts
				(xy 0.5334 0.254) (xy 0.635 0.254) (xy 0.635 0.2286) (xy 0.635 -0.254) (xy 0.5334 -0.254) (xy 0.5334 -0.2794)
				(xy -0.5334 -0.2794) (xy -0.5334 -0.254) (xy -0.635 -0.254) (xy -0.635 0.254) (xy -0.5334 0.254)
				(xy -0.5334 0.2794) (xy 0.508 0.2794) (xy 0.5334 0.2794)
			)
			(stroke
				(width 0)
				(type default)
			)
			(fill no)
			(layer "B.CrtYd")
		)
		(pad "1" smd rect
			(at -0.40005 0 180)
			(size 0.4572 0.508)
			(layers "B.Cu" "B.Mask" "B.Paste")
			(net "P1V05_NODE1")
		)
		(pad "2" smd rect
			(at 0.40005 0 180)
			(size 0.4572 0.508)
			(layers "B.Cu" "B.Mask" "B.Paste")
			(net "GND")
		)
	)
	(footprint ""
		(layer "B.Cu")
		(at 71.645526 -83.960208 180)
		(property "Reference" "R77"
			(at -2.476754 1.427988 0)
			(unlocked yes)
			(layer "B.SilkS")
			(effects
				(font
					(size 0.7874 0.5842)
					(thickness 0.1524)
				)
				(justify left mirror)
			)
		)
		(property "Value" ""
			(at 0 0 0)
			(layer "B.Fab")
			(effects
				(font
					(size 1.27 1.27)
				)
				(justify mirror)
			)
		)
		(duplicate_pad_numbers_are_jumpers no)
		(fp_line
			(start 0.7874 0.4064)
			(end 0.7874 -0.4064)
			(stroke
				(width 0.1524)
				(type default)
			)
			(layer "B.SilkS")
		)
		(fp_line
			(start 0.7874 -0.4064)
			(end -0.7874 -0.4064)
			(stroke
				(width 0.1524)
				(type default)
			)
			(layer "B.SilkS")
		)
		(fp_line
			(start -0.7874 0.4064)
			(end 0.7874 0.4064)
			(stroke
				(width 0.1524)
				(type default)
			)
			(layer "B.SilkS")
		)
		(fp_line
			(start -0.7874 -0.4064)
			(end -0.7874 0.4064)
			(stroke
				(width 0.1524)
				(type default)
			)
			(layer "B.SilkS")
		)
		(fp_poly
			(pts
				(xy 0.508 0.2794) (xy 0.508 0.2286) (xy 0.635 0.2286) (xy 0.635 -0.254) (xy 0.5334 -0.254) (xy 0.5334 -0.2794)
				(xy -0.5334 -0.2794) (xy -0.5334 -0.254) (xy -0.635 -0.254) (xy -0.635 0.254) (xy -0.5334 0.254)
				(xy -0.5334 0.2794)
			)
			(stroke
				(width 0)
				(type default)
			)
			(fill no)
			(layer "B.CrtYd")
		)
		(pad "1" smd rect
			(at -0.40005 0)
			(size 0.4572 0.508)
			(layers "B.Cu" "B.Mask" "B.Paste")
			(net "P3V3_SUS_NODE1")
		)
		(pad "2" smd rect
			(at 0.40005 0)
			(size 0.4572 0.508)
			(layers "B.Cu" "B.Mask" "B.Paste")
			(net "VR_NODE1_VDDR_1V5_CNTL")
		)
	)
	(footprint ""
		(layer "B.Cu")
		(at 160.67278 -148.854922 90)
		(property "Reference" "C463"
			(at -8.519922 -0.503174 270)
			(unlocked yes)
			(layer "B.SilkS")
			(effects
				(font
					(size 0.7874 0.5842)
					(thickness 0.1524)
				)
				(justify left mirror)
			)
		)
		(property "Value" ""
			(at 0 0 90)
			(layer "B.Fab")
			(effects
				(font
					(size 1.27 1.27)
				)
				(justify mirror)
			)
		)
		(duplicate_pad_numbers_are_jumpers no)
		(fp_line
			(start 0.7874 -0.4064)
			(end -0.7874 -0.4064)
			(stroke
				(width 0.1524)
				(type default)
			)
			(layer "B.SilkS")
		)
		(fp_line
			(start -0.7874 -0.4064)
			(end -0.7874 0.4064)
			(stroke
				(width 0.1524)
				(type default)
			)
			(layer "B.SilkS")
		)
		(fp_line
			(start 0 0.381)
			(end 0 -0.381)
			(stroke
				(width 0.1524)
				(type default)
			)
			(layer "B.SilkS")
		)
		(fp_line
			(start 0.7874 0.4064)
			(end 0.7874 -0.4064)
			(stroke
				(width 0.1524)
				(type default)
			)
			(layer "B.SilkS")
		)
		(fp_line
			(start -0.7874 0.4064)
			(end 0.7874 0.4064)
			(stroke
				(width 0.1524)
				(type default)
			)
			(layer "B.SilkS")
		)
		(fp_poly
			(pts
				(xy 0.5334 0.254) (xy 0.635 0.254) (xy 0.635 0.2286) (xy 0.635 -0.254) (xy 0.5334 -0.254) (xy 0.5334 -0.2794)
				(xy -0.5334 -0.2794) (xy -0.5334 -0.254) (xy -0.635 -0.254) (xy -0.635 0.254) (xy -0.5334 0.254)
				(xy -0.5334 0.2794) (xy 0.508 0.2794) (xy 0.5334 0.2794)
			)
			(stroke
				(width 0)
				(type default)
			)
			(fill no)
			(layer "B.CrtYd")
		)
		(pad "1" smd rect
			(at -0.40005 0 270)
			(size 0.4572 0.508)
			(layers "B.Cu" "B.Mask" "B.Paste")
			(net "P1V05_LAN2")
		)
		(pad "2" smd rect
			(at 0.40005 0 270)
			(size 0.4572 0.508)
			(layers "B.Cu" "B.Mask" "B.Paste")
			(net "GND")
		)
	)
	(footprint ""
		(layer "B.Cu")
		(at 72.186546 -27.351736 -90)
		(property "Reference" "C169"
			(at -1.096772 0.018796 270)
			(unlocked yes)
			(layer "B.SilkS")
			(effects
				(font
					(size 0.7874 0.5842)
					(thickness 0.1524)
				)
				(justify left mirror)
			)
		)
		(property "Value" ""
			(at 0 0 90)
			(layer "B.Fab")
			(effects
				(font
					(size 1.27 1.27)
				)
				(justify mirror)
			)
		)
		(duplicate_pad_numbers_are_jumpers no)
		(fp_line
			(start -0.7874 0.4064)
			(end 0.7874 0.4064)
			(stroke
				(width 0.1524)
				(type default)
			)
			(layer "B.SilkS")
		)
		(fp_line
			(start 0.7874 0.4064)
			(end 0.7874 -0.4064)
			(stroke
				(width 0.1524)
				(type default)
			)
			(layer "B.SilkS")
		)
		(fp_line
			(start 0 0.381)
			(end 0 -0.381)
			(stroke
				(width 0.1524)
				(type default)
			)
			(layer "B.SilkS")
		)
		(fp_line
			(start -0.7874 -0.4064)
			(end -0.7874 0.4064)
			(stroke
				(width 0.1524)
				(type default)
			)
			(layer "B.SilkS")
		)
		(fp_line
			(start 0.7874 -0.4064)
			(end -0.7874 -0.4064)
			(stroke
				(width 0.1524)
				(type default)
			)
			(layer "B.SilkS")
		)
		(fp_poly
			(pts
				(xy 0.5334 0.254) (xy 0.635 0.254) (xy 0.635 0.2286) (xy 0.635 -0.254) (xy 0.5334 -0.254) (xy 0.5334 -0.2794)
				(xy -0.5334 -0.2794) (xy -0.5334 -0.254) (xy -0.635 -0.254) (xy -0.635 0.254) (xy -0.5334 0.254)
				(xy -0.5334 0.2794) (xy 0.508 0.2794) (xy 0.5334 0.2794)
			)
			(stroke
				(width 0)
				(type default)
			)
			(fill no)
			(layer "B.CrtYd")
		)
		(pad "1" smd rect
			(at -0.40005 0 90)
			(size 0.4572 0.508)
			(layers "B.Cu" "B.Mask" "B.Paste")
			(net "PV_VDDR_NODE1")
		)
		(pad "2" smd rect
			(at 0.40005 0 90)
			(size 0.4572 0.508)
			(layers "B.Cu" "B.Mask" "B.Paste")
			(net "GND")
		)
	)
	(footprint ""
		(layer "B.Cu")
		(at 63.832486 -121.044462 90)
		(property "Reference" "R321"
			(at -7.37235 10.08634 270)
			(unlocked yes)
			(layer "B.SilkS")
			(effects
				(font
					(size 0.7874 0.5842)
					(thickness 0.1524)
				)
				(justify left mirror)
			)
		)
		(property "Value" ""
			(at 0 0 90)
			(layer "B.Fab")
			(effects
				(font
					(size 1.27 1.27)
				)
				(justify mirror)
			)
		)
		(duplicate_pad_numbers_are_jumpers no)
		(fp_line
			(start 0.7874 -0.4064)
			(end -0.7874 -0.4064)
			(stroke
				(width 0.1524)
				(type default)
			)
			(layer "B.SilkS")
		)
		(fp_line
			(start -0.7874 -0.4064)
			(end -0.7874 0.4064)
			(stroke
				(width 0.1524)
				(type default)
			)
			(layer "B.SilkS")
		)
		(fp_line
			(start 0.7874 0.4064)
			(end 0.7874 -0.4064)
			(stroke
				(width 0.1524)
				(type default)
			)
			(layer "B.SilkS")
		)
		(fp_line
			(start -0.7874 0.4064)
			(end 0.7874 0.4064)
			(stroke
				(width 0.1524)
				(type default)
			)
			(layer "B.SilkS")
		)
		(fp_poly
			(pts
				(xy 0.508 0.2794) (xy 0.508 0.2286) (xy 0.635 0.2286) (xy 0.635 -0.254) (xy 0.5334 -0.254) (xy 0.5334 -0.2794)
				(xy -0.5334 -0.2794) (xy -0.5334 -0.254) (xy -0.635 -0.254) (xy -0.635 0.254) (xy -0.5334 0.254)
				(xy -0.5334 0.2794)
			)
			(stroke
				(width 0)
				(type default)
			)
			(fill no)
			(layer "B.CrtYd")
		)
		(pad "1" smd rect
			(at -0.40005 0 270)
			(size 0.4572 0.508)
			(layers "B.Cu" "B.Mask" "B.Paste")
			(net "P3V3_NODE1")
		)
		(pad "2" smd rect
			(at 0.40005 0 270)
			(size 0.4572 0.508)
			(layers "B.Cu" "B.Mask" "B.Paste")
			(net "BMC_ROMA5")
		)
	)
	(footprint ""
		(layer "B.Cu")
		(at 54.16931 -68.50507 -90)
		(property "Reference" "C95"
			(at 32.190436 14.44752 270)
			(unlocked yes)
			(layer "B.SilkS")
			(effects
				(font
					(size 0.7874 0.5842)
					(thickness 0.1524)
				)
				(justify left mirror)
			)
		)
		(property "Value" ""
			(at 0 0 90)
			(layer "B.Fab")
			(effects
				(font
					(size 1.27 1.27)
				)
				(justify mirror)
			)
		)
		(duplicate_pad_numbers_are_jumpers no)
		(fp_line
			(start -0.7874 0.4064)
			(end 0.7874 0.4064)
			(stroke
				(width 0.1524)
				(type default)
			)
			(layer "B.SilkS")
		)
		(fp_line
			(start 0.7874 0.4064)
			(end 0.7874 -0.4064)
			(stroke
				(width 0.1524)
				(type default)
			)
			(layer "B.SilkS")
		)
		(fp_line
			(start 0 0.381)
			(end 0 -0.381)
			(stroke
				(width 0.1524)
				(type default)
			)
			(layer "B.SilkS")
		)
		(fp_line
			(start -0.7874 -0.4064)
			(end -0.7874 0.4064)
			(stroke
				(width 0.1524)
				(type default)
			)
			(layer "B.SilkS")
		)
		(fp_line
			(start 0.7874 -0.4064)
			(end -0.7874 -0.4064)
			(stroke
				(width 0.1524)
				(type default)
			)
			(layer "B.SilkS")
		)
		(fp_poly
			(pts
				(xy 0.5334 0.254) (xy 0.635 0.254) (xy 0.635 0.2286) (xy 0.635 -0.254) (xy 0.5334 -0.254) (xy 0.5334 -0.2794)
				(xy -0.5334 -0.2794) (xy -0.5334 -0.254) (xy -0.635 -0.254) (xy -0.635 0.254) (xy -0.5334 0.254)
				(xy -0.5334 0.2794) (xy 0.508 0.2794) (xy 0.5334 0.2794)
			)
			(stroke
				(width 0)
				(type default)
			)
			(fill no)
			(layer "B.CrtYd")
		)
		(pad "1" smd rect
			(at -0.40005 0 90)
			(size 0.4572 0.508)
			(layers "B.Cu" "B.Mask" "B.Paste")
			(net "P1V5_SUS_NODE1")
		)
		(pad "2" smd rect
			(at 0.40005 0 90)
			(size 0.4572 0.508)
			(layers "B.Cu" "B.Mask" "B.Paste")
			(net "GND")
		)
	)
	(footprint ""
		(layer "B.Cu")
		(at 83.05927 -21.09724 90)
		(property "Reference" "C147"
			(at -5.738114 -0.62992 270)
			(unlocked yes)
			(layer "B.SilkS")
			(effects
				(font
					(size 0.7874 0.5842)
					(thickness 0.1524)
				)
				(justify left mirror)
			)
		)
		(property "Value" ""
			(at 0 0 90)
			(layer "B.Fab")
			(effects
				(font
					(size 1.27 1.27)
				)
				(justify mirror)
			)
		)
		(duplicate_pad_numbers_are_jumpers no)
		(fp_line
			(start 0.7874 -0.4064)
			(end -0.7874 -0.4064)
			(stroke
				(width 0.1524)
				(type default)
			)
			(layer "B.SilkS")
		)
		(fp_line
			(start -0.7874 -0.4064)
			(end -0.7874 0.4064)
			(stroke
				(width 0.1524)
				(type default)
			)
			(layer "B.SilkS")
		)
		(fp_line
			(start 0 0.381)
			(end 0 -0.381)
			(stroke
				(width 0.1524)
				(type default)
			)
			(layer "B.SilkS")
		)
		(fp_line
			(start 0.7874 0.4064)
			(end 0.7874 -0.4064)
			(stroke
				(width 0.1524)
				(type default)
			)
			(layer "B.SilkS")
		)
		(fp_line
			(start -0.7874 0.4064)
			(end 0.7874 0.4064)
			(stroke
				(width 0.1524)
				(type default)
			)
			(layer "B.SilkS")
		)
		(fp_poly
			(pts
				(xy 0.5334 0.254) (xy 0.635 0.254) (xy 0.635 0.2286) (xy 0.635 -0.254) (xy 0.5334 -0.254) (xy 0.5334 -0.2794)
				(xy -0.5334 -0.2794) (xy -0.5334 -0.254) (xy -0.635 -0.254) (xy -0.635 0.254) (xy -0.5334 0.254)
				(xy -0.5334 0.2794) (xy 0.508 0.2794) (xy 0.5334 0.2794)
			)
			(stroke
				(width 0)
				(type default)
			)
			(fill no)
			(layer "B.CrtYd")
		)
		(pad "1" smd rect
			(at -0.40005 0 270)
			(size 0.4572 0.508)
			(layers "B.Cu" "B.Mask" "B.Paste")
			(net "PV_VDDR_NODE1")
		)
		(pad "2" smd rect
			(at 0.40005 0 270)
			(size 0.4572 0.508)
			(layers "B.Cu" "B.Mask" "B.Paste")
			(net "GND")
		)
	)
	(footprint ""
		(layer "B.Cu")
		(at 76.7461 -164.132768)
		(property "Reference" "R622"
			(at -1.420368 0.208026 0)
			(unlocked yes)
			(layer "B.SilkS")
			(effects
				(font
					(size 0.7874 0.5842)
					(thickness 0.1524)
				)
				(justify left mirror)
			)
		)
		(property "Value" ""
			(at 0 0 0)
			(layer "B.Fab")
			(effects
				(font
					(size 1.27 1.27)
				)
				(justify mirror)
			)
		)
		(duplicate_pad_numbers_are_jumpers no)
		(fp_line
			(start -0.7874 -0.4064)
			(end -0.7874 0.4064)
			(stroke
				(width 0.1524)
				(type default)
			)
			(layer "B.SilkS")
		)
		(fp_line
			(start -0.7874 0.4064)
			(end 0.7874 0.4064)
			(stroke
				(width 0.1524)
				(type default)
			)
			(layer "B.SilkS")
		)
		(fp_line
			(start 0.7874 -0.4064)
			(end -0.7874 -0.4064)
			(stroke
				(width 0.1524)
				(type default)
			)
			(layer "B.SilkS")
		)
		(fp_line
			(start 0.7874 0.4064)
			(end 0.7874 -0.4064)
			(stroke
				(width 0.1524)
				(type default)
			)
			(layer "B.SilkS")
		)
		(fp_poly
			(pts
				(xy 0.508 0.2794) (xy 0.508 0.2286) (xy 0.635 0.2286) (xy 0.635 -0.254) (xy 0.5334 -0.254) (xy 0.5334 -0.2794)
				(xy -0.5334 -0.2794) (xy -0.5334 -0.254) (xy -0.635 -0.254) (xy -0.635 0.254) (xy -0.5334 0.254)
				(xy -0.5334 0.2794)
			)
			(stroke
				(width 0)
				(type default)
			)
			(fill no)
			(layer "B.CrtYd")
		)
		(pad "1" smd rect
			(at -0.40005 0 180)
			(size 0.4572 0.508)
			(layers "B.Cu" "B.Mask" "B.Paste")
			(net "CPLD_WDT2")
		)
		(pad "2" smd rect
			(at 0.40005 0 180)
			(size 0.4572 0.508)
			(layers "B.Cu" "B.Mask" "B.Paste")
			(net "CPLD_WDT2_R")
		)
	)
	(footprint ""
		(layer "B.Cu")
		(at 39.120572 -67.941698 180)
		(property "Reference" "C15"
			(at -3.128264 -0.293116 0)
			(unlocked yes)
			(layer "B.SilkS")
			(effects
				(font
					(size 0.7874 0.5842)
					(thickness 0.1524)
				)
				(justify left mirror)
			)
		)
		(property "Value" ""
			(at 0 0 0)
			(layer "B.Fab")
			(effects
				(font
					(size 1.27 1.27)
				)
				(justify mirror)
			)
		)
		(duplicate_pad_numbers_are_jumpers no)
		(fp_line
			(start 0.7874 0.4064)
			(end 0.7874 -0.4064)
			(stroke
				(width 0.1524)
				(type default)
			)
			(layer "B.SilkS")
		)
		(fp_line
			(start 0.7874 -0.4064)
			(end -0.7874 -0.4064)
			(stroke
				(width 0.1524)
				(type default)
			)
			(layer "B.SilkS")
		)
		(fp_line
			(start 0 0.381)
			(end 0 -0.381)
			(stroke
				(width 0.1524)
				(type default)
			)
			(layer "B.SilkS")
		)
		(fp_line
			(start -0.7874 0.4064)
			(end 0.7874 0.4064)
			(stroke
				(width 0.1524)
				(type default)
			)
			(layer "B.SilkS")
		)
		(fp_line
			(start -0.7874 -0.4064)
			(end -0.7874 0.4064)
			(stroke
				(width 0.1524)
				(type default)
			)
			(layer "B.SilkS")
		)
		(fp_poly
			(pts
				(xy 0.5334 0.254) (xy 0.635 0.254) (xy 0.635 0.2286) (xy 0.635 -0.254) (xy 0.5334 -0.254) (xy 0.5334 -0.2794)
				(xy -0.5334 -0.2794) (xy -0.5334 -0.254) (xy -0.635 -0.254) (xy -0.635 0.254) (xy -0.5334 0.254)
				(xy -0.5334 0.2794) (xy 0.508 0.2794) (xy 0.5334 0.2794)
			)
			(stroke
				(width 0)
				(type default)
			)
			(fill no)
			(layer "B.CrtYd")
		)
		(pad "1" smd rect
			(at -0.40005 0)
			(size 0.4572 0.508)
			(layers "B.Cu" "B.Mask" "B.Paste")
			(net "P2E_CPU_PCIE_SW_NODE1_TX_C_DP")
		)
		(pad "2" smd rect
			(at 0.40005 0)
			(size 0.4572 0.508)
			(layers "B.Cu" "B.Mask" "B.Paste")
			(net "P2E_CPU_PCIE_SW_NODE1_TX_DP")
		)
	)
)
